# T6G (Grand Teton) — schematic netlist excerpt (pin names and nets, part order shuffled) for the footprints in the layout excerpt that follows; sources: Cadence DE-HDL packaged netlist, KiCad conversion of 04192023_DAF0TMB3IC0_F0TG_MB_C_brd_V02_OCP.brd

U9002  74LVC1G32GW  IC  pkg SMLF  page 136
  I0  = HP_LVC3_OCP_V3_1_PWRGD_R1
  I1  = FM_PLD_OCP_SFF_AUX_PWR_EN
  GND  = GND
  O  = OCP_SFF_AUX_PWR_EN_R3
  VCC  = P3V3_AUX

R6703  Q_RES  0 5% EMPTY  pkg 0402LF  page 323 : A = P1V8_CPU1_RT0_1A_1D ; B = P1V8_CPU1_RT0_1A
C1566  Q_CAP_DIFFBUS  DIFF BUS_0.22UF 6.3V 20% X6S  pkg C0201  page 65 : \1\ = P5E_CPU0_G3_TX_C_DN<6> ; \2\ = P5E_CPU0_G3_TX_DN<6>

(kicad_pcb
	(version 20260206)
	(generator "pcbnew")
	(generator_version "10.0")
	(general
		(thickness 1.6)
		(legacy_teardrops no)
	)
	(paper "A4")
	(title_block
		(title "04192023_DAF0TMB3IC0_F0TG_MB_C_brd_V02_OCP.brd")
		(comment 1 "Grand Teton / footprints 2041-2043 of 8354")
	)
	(layers
		(0 "F.Cu" signal "TOP")
		(4 "In1.Cu" signal "GND")
		(6 "In2.Cu" signal "IN1")
		(8 "In3.Cu" signal "GND1")
		(10 "In4.Cu" signal "IN2")
		(12 "In5.Cu" signal "GND2")
		(14 "In6.Cu" signal "IN3")
		(16 "In7.Cu" signal "GND3")
		(18 "In8.Cu" signal "VCC")
		(20 "In9.Cu" signal "VCC1")
		(22 "In10.Cu" signal "GND4")
		(24 "In11.Cu" signal "IN4")
		(26 "In12.Cu" signal "GND5")
		(28 "In13.Cu" signal "IN5")
		(30 "In14.Cu" signal "GND6")
		(32 "In15.Cu" signal "IN6")
		(34 "In16.Cu" signal "GND7")
		(2 "B.Cu" signal "BOTTOM")
		(9 "F.Adhes" user "F.Adhesive")
		(11 "B.Adhes" user "B.Adhesive")
		(13 "F.Paste" user "Package Geometry/Pastemask Top")
		(15 "B.Paste" user "Package Geometry/Pastemask Bottom")
		(5 "F.SilkS" user "Ref Des/Silkscreen Top")
		(7 "B.SilkS" user "Ref Des/Silkscreen Bottom")
		(1 "F.Mask" user "Board Geometry/Soldermask Top")
		(3 "B.Mask" user "Board Geometry/Soldermask Bottom")
		(17 "Dwgs.User" user "User.Drawings")
		(19 "Cmts.User" user "User.Comments")
		(21 "Eco1.User" user "User.Eco1")
		(23 "Eco2.User" user "User.Eco2")
		(25 "Edge.Cuts" user "Board Geometry/Outline")
		(27 "Margin" user)
		(31 "F.CrtYd" user "Package Geometry/Place Bound Top")
		(29 "B.CrtYd" user "Package Geometry/Place Bound Bottom")
		(35 "F.Fab" user "Ref Des/Assembly Top")
		(33 "B.Fab" user "Ref Des/Assembly Bottom")
	)
	(footprint ""
		(layer "F.Cu")
		(at 69.862446 -384.10388 180)
		(property "Reference" "R6703"
			(at 0 0 180)
			(layer "F.SilkS")
			(hide yes)
			(effects
				(font
					(size 1.27 1.27)
				)
			)
		)
		(property "Value" ""
			(at 0 0 180)
			(layer "F.Fab")
			(effects
				(font
					(size 1.27 1.27)
				)
			)
		)
		(duplicate_pad_numbers_are_jumpers no)
		(fp_line
			(start 0.7874 0.4064)
			(end -0.7874 0.4064)
			(stroke
				(width 0.1524)
				(type default)
			)
			(layer "F.SilkS")
		)
		(fp_line
			(start 0.7874 -0.4064)
			(end 0.7874 0.4064)
			(stroke
				(width 0.1524)
				(type default)
			)
			(layer "F.SilkS")
		)
		(fp_line
			(start -0.7874 0.4064)
			(end -0.7874 -0.4064)
			(stroke
				(width 0.1524)
				(type default)
			)
			(layer "F.SilkS")
		)
		(fp_line
			(start -0.7874 -0.4064)
			(end 0.7874 -0.4064)
			(stroke
				(width 0.1524)
				(type default)
			)
			(layer "F.SilkS")
		)
		(fp_line
			(start 0.67945 0.3048)
			(end 0.120396 0.3048)
			(stroke
				(width 0.1)
				(type default)
			)
			(layer "F.Fab")
		)
		(fp_line
			(start 0.67945 -0.3048)
			(end 0.67945 0.3048)
			(stroke
				(width 0.1)
				(type default)
			)
			(layer "F.Fab")
		)
		(fp_line
			(start 0.12065 -0.2794)
			(end 0.12065 -0.3048)
			(stroke
				(width 0.1)
				(type default)
			)
			(layer "F.Fab")
		)
		(fp_line
			(start 0.12065 -0.3048)
			(end 0.67945 -0.3048)
			(stroke
				(width 0.1)
				(type default)
			)
			(layer "F.Fab")
		)
		(fp_line
			(start 0.120396 0.3048)
			(end 0.120396 0.2794)
			(stroke
				(width 0.1)
				(type default)
			)
			(layer "F.Fab")
		)
		(fp_line
			(start 0.120396 0.2794)
			(end -0.12065 0.2794)
			(stroke
				(width 0.1)
				(type default)
			)
			(layer "F.Fab")
		)
		(fp_line
			(start -0.12065 0.3048)
			(end -0.67945 0.3048)
			(stroke
				(width 0.1)
				(type default)
			)
			(layer "F.Fab")
		)
		(fp_line
			(start -0.12065 0.2794)
			(end -0.12065 0.3048)
			(stroke
				(width 0.1)
				(type default)
			)
			(layer "F.Fab")
		)
		(fp_line
			(start -0.12065 -0.2794)
			(end 0.12065 -0.2794)
			(stroke
				(width 0.1)
				(type default)
			)
			(layer "F.Fab")
		)
		(fp_line
			(start -0.12065 -0.305054)
			(end -0.12065 -0.2794)
			(stroke
				(width 0.1)
				(type default)
			)
			(layer "F.Fab")
		)
		(fp_line
			(start -0.67945 0.3048)
			(end -0.67945 -0.305054)
			(stroke
				(width 0.1)
				(type default)
			)
			(layer "F.Fab")
		)
		(fp_line
			(start -0.67945 -0.305054)
			(end -0.12065 -0.305054)
			(stroke
				(width 0.1)
				(type default)
			)
			(layer "F.Fab")
		)
		(pad "1" smd rect
			(at -0.40005 0)
			(size 0.4572 0.508)
			(layers "F.Cu" "F.Mask" "F.Paste")
			(net "P1V8_CPU1_RT0_1A_1D")
		)
		(pad "2" smd rect
			(at 0.40005 0)
			(size 0.4572 0.508)
			(layers "F.Cu" "F.Mask" "F.Paste")
			(net "P1V8_CPU1_RT0_1A")
		)
	)
	(footprint ""
		(layer "F.Cu")
		(at 215.646 -99.822)
		(property "Reference" "U9002"
			(at -0.88519 -1.39446 90)
			(unlocked yes)
			(layer "F.SilkS")
			(effects
				(font
					(size 0.7874 0.5842)
					(thickness 0.1524)
				)
				(justify left)
			)
		)
		(property "Value" ""
			(at 0 0 0)
			(layer "F.Fab")
			(effects
				(font
					(size 1.27 1.27)
				)
			)
		)
		(duplicate_pad_numbers_are_jumpers no)
		(fp_line
			(start -1.4986 -1.100074)
			(end 1.4986 -1.100074)
			(stroke
				(width 0.1524)
				(type default)
			)
			(layer "F.SilkS")
		)
		(fp_line
			(start -1.4986 1.100074)
			(end -1.4986 -1.100074)
			(stroke
				(width 0.1524)
				(type default)
			)
			(layer "F.SilkS")
		)
		(fp_line
			(start 1.4986 -1.100074)
			(end 1.4986 1.100074)
			(stroke
				(width 0.1524)
				(type default)
			)
			(layer "F.SilkS")
		)
		(fp_line
			(start 1.4986 1.100074)
			(end -1.4986 1.100074)
			(stroke
				(width 0.1524)
				(type default)
			)
			(layer "F.SilkS")
		)
		(fp_poly
			(pts
				(xy -2.378456 -0.7366) (xy -2.169922 -1.325372) (xy -1.757426 -0.831342)
			)
			(stroke
				(width 0)
				(type default)
			)
			(fill yes)
			(layer "F.SilkS")
		)
		(fp_line
			(start -0.67437 -1.100074)
			(end 0.67437 -1.100074)
			(stroke
				(width 0.1)
				(type default)
			)
			(layer "F.Fab")
		)
		(fp_line
			(start -0.67437 1.100074)
			(end -0.67437 -1.100074)
			(stroke
				(width 0.1)
				(type default)
			)
			(layer "F.Fab")
		)
		(fp_line
			(start 0.67437 -1.100074)
			(end 0.67437 1.100074)
			(stroke
				(width 0.1)
				(type default)
			)
			(layer "F.Fab")
		)
		(fp_line
			(start 0.67437 1.100074)
			(end -0.67437 1.100074)
			(stroke
				(width 0.1)
				(type default)
			)
			(layer "F.Fab")
		)
		(fp_poly
			(pts
				(xy -2.20472 -0.338328) (xy -2.20472 -0.963168) (xy -1.651 -0.635)
			)
			(stroke
				(width 0)
				(type default)
			)
			(fill yes)
			(layer "F.Fab")
		)
		(pad "1" smd rect
			(at -0.889 -0.649986)
			(size 1.016 0.381)
			(layers "F.Cu" "F.Mask" "F.Paste")
			(net "HP_LVC3_OCP_V3_1_PWRGD_R1")
		)
		(pad "2" smd rect
			(at -0.889 0)
			(size 1.016 0.381)
			(layers "F.Cu" "F.Mask" "F.Paste")
			(net "FM_PLD_OCP_SFF_AUX_PWR_EN")
		)
		(pad "3" smd rect
			(at -0.889 0.649986)
			(size 1.016 0.381)
			(layers "F.Cu" "F.Mask" "F.Paste")
			(net "GND")
		)
		(pad "4" smd rect
			(at 0.889 0.649986)
			(size 1.016 0.381)
			(layers "F.Cu" "F.Mask" "F.Paste")
			(net "OCP_SFF_AUX_PWR_EN_R3")
		)
		(pad "5" smd rect
			(at 0.889 -0.649986)
			(size 1.016 0.381)
			(layers "F.Cu" "F.Mask" "F.Paste")
			(net "P3V3_AUX")
		)
	)
	(footprint ""
		(layer "F.Cu")
		(at 415.459164 -17.624298 90)
		(property "Reference" "C1566"
			(at 0 0 90)
			(layer "F.SilkS")
			(hide yes)
			(effects
				(font
					(size 1.27 1.27)
				)
			)
		)
		(property "Value" ""
			(at 0 0 90)
			(layer "F.Fab")
			(effects
				(font
					(size 1.27 1.27)
				)
			)
		)
		(duplicate_pad_numbers_are_jumpers no)
		(fp_line
			(start 0.299974 -0.150114)
			(end 0.299974 0.150114)
			(stroke
				(width 0.1)
				(type default)
			)
			(layer "F.Fab")
		)
		(fp_line
			(start -0.299974 -0.150114)
			(end 0.299974 -0.150114)
			(stroke
				(width 0.1)
				(type default)
			)
			(layer "F.Fab")
		)
		(fp_line
			(start 0.299974 0.150114)
			(end -0.299974 0.150114)
			(stroke
				(width 0.1)
				(type default)
			)
			(layer "F.Fab")
		)
		(fp_line
			(start -0.299974 0.150114)
			(end -0.299974 -0.150114)
			(stroke
				(width 0.1)
				(type default)
			)
			(layer "F.Fab")
		)
		(pad "1" smd rect
			(at -0.2667 0 90)
			(size 0.3048 0.381)
			(layers "F.Cu" "F.Mask" "F.Paste")
			(net "P5E_CPU0_G3_TX_C_DN<6>")
		)
		(pad "2" smd rect
			(at 0.2667 0 90)
			(size 0.3048 0.381)
			(layers "F.Cu" "F.Mask" "F.Paste")
			(net "P5E_CPU0_G3_TX_DN<6>")
		)
	)
)
